# S9S_MB_2U (Grand Teton) — schematic netlist excerpt (pin names and nets, part order shuffled) for the footprints in the layout excerpt that follows; sources: Cadence DE-HDL packaged netlist, KiCad conversion of 03242023_DA0F0TMBIJ0_F0T_Motherboard_J_brd_V01_OCP.brd

R3457  Q_RES  10K 1% CHIP  pkg 0402LF  page 149 : A = GPU_BASE_STBY_EN_BUF_R ; B = GND

(kicad_pcb
	(version 20260206)
	(generator "pcbnew")
	(generator_version "10.0")
	(general
		(thickness 1.6)
		(legacy_teardrops no)
	)
	(paper "A4")
	(title_block
		(title "03242023_DA0F0TMBIJ0_F0T_Motherboard_J_brd_V01_OCP.brd")
		(comment 1 "Grand Teton / footprints 4005-4005 of 6105")
	)
	(layers
		(0 "F.Cu" signal "TOP")
		(4 "In1.Cu" signal "GND")
		(6 "In2.Cu" signal "IN1")
		(8 "In3.Cu" signal "GND1")
		(10 "In4.Cu" signal "IN2")
		(12 "In5.Cu" signal "GND2")
		(14 "In6.Cu" signal "IN3")
		(16 "In7.Cu" signal "GND3")
		(18 "In8.Cu" signal "VCC")
		(20 "In9.Cu" signal "VCC1")
		(22 "In10.Cu" signal "GND4")
		(24 "In11.Cu" signal "IN4")
		(26 "In12.Cu" signal "GND5")
		(28 "In13.Cu" signal "IN5")
		(30 "In14.Cu" signal "GND6")
		(32 "In15.Cu" signal "IN6")
		(34 "In16.Cu" signal "GND7")
		(2 "B.Cu" signal "BOTTOM")
		(9 "F.Adhes" user "F.Adhesive")
		(11 "B.Adhes" user "B.Adhesive")
		(13 "F.Paste" user "Package Geometry/Pastemask Top")
		(15 "B.Paste" user "Package Geometry/Pastemask Bottom")
		(5 "F.SilkS" user "Ref Des/Silkscreen Top")
		(7 "B.SilkS" user "Ref Des/Silkscreen Bottom")
		(1 "F.Mask" user "Board Geometry/Soldermask Top")
		(3 "B.Mask" user "Board Geometry/Soldermask Bottom")
		(17 "Dwgs.User" user "User.Drawings")
		(19 "Cmts.User" user "User.Comments")
		(21 "Eco1.User" user "User.Eco1")
		(23 "Eco2.User" user "User.Eco2")
		(25 "Edge.Cuts" user "Board Geometry/Outline")
		(27 "Margin" user)
		(31 "F.CrtYd" user "Package Geometry/Place Bound Top")
		(29 "B.CrtYd" user "Package Geometry/Place Bound Bottom")
		(35 "F.Fab" user "Ref Des/Assembly Top")
		(33 "B.Fab" user "Ref Des/Assembly Bottom")
	)
	(footprint ""
		(layer "F.Cu")
		(at 170.23588 -433.923948)
		(property "Reference" "R3457"
			(at 0 0 0)
			(layer "F.SilkS")
			(hide yes)
			(effects
				(font
					(size 1.27 1.27)
				)
			)
		)
		(property "Value" ""
			(at 0 0 0)
			(layer "F.Fab")
			(effects
				(font
					(size 1.27 1.27)
				)
			)
		)
		(duplicate_pad_numbers_are_jumpers no)
		(fp_line
			(start -0.7874 -0.4064)
			(end 0.7874 -0.4064)
			(stroke
				(width 0.1524)
				(type default)
			)
			(layer "F.SilkS")
		)
		(fp_line
			(start -0.7874 0.4064)
			(end -0.7874 -0.4064)
			(stroke
				(width 0.1524)
				(type default)
			)
			(layer "F.SilkS")
		)
		(fp_line
			(start 0.7874 -0.4064)
			(end 0.7874 0.4064)
			(stroke
				(width 0.1524)
				(type default)
			)
			(layer "F.SilkS")
		)
		(fp_line
			(start 0.7874 0.4064)
			(end -0.7874 0.4064)
			(stroke
				(width 0.1524)
				(type default)
			)
			(layer "F.SilkS")
		)
		(fp_line
			(start -0.67945 -0.305054)
			(end -0.12065 -0.305054)
			(stroke
				(width 0.1)
				(type default)
			)
			(layer "F.Fab")
		)
		(fp_line
			(start -0.67945 0.3048)
			(end -0.67945 -0.305054)
			(stroke
				(width 0.1)
				(type default)
			)
			(layer "F.Fab")
		)
		(fp_line
			(start -0.12065 -0.305054)
			(end -0.12065 -0.2794)
			(stroke
				(width 0.1)
				(type default)
			)
			(layer "F.Fab")
		)
		(fp_line
			(start -0.12065 -0.2794)
			(end 0.12065 -0.2794)
			(stroke
				(width 0.1)
				(type default)
			)
			(layer "F.Fab")
		)
		(fp_line
			(start -0.12065 0.2794)
			(end -0.12065 0.3048)
			(stroke
				(width 0.1)
				(type default)
			)
			(layer "F.Fab")
		)
		(fp_line
			(start -0.12065 0.3048)
			(end -0.67945 0.3048)
			(stroke
				(width 0.1)
				(type default)
			)
			(layer "F.Fab")
		)
		(fp_line
			(start 0.120396 0.2794)
			(end -0.12065 0.2794)
			(stroke
				(width 0.1)
				(type default)
			)
			(layer "F.Fab")
		)
		(fp_line
			(start 0.120396 0.3048)
			(end 0.120396 0.2794)
			(stroke
				(width 0.1)
				(type default)
			)
			(layer "F.Fab")
		)
		(fp_line
			(start 0.12065 -0.3048)
			(end 0.67945 -0.3048)
			(stroke
				(width 0.1)
				(type default)
			)
			(layer "F.Fab")
		)
		(fp_line
			(start 0.12065 -0.2794)
			(end 0.12065 -0.3048)
			(stroke
				(width 0.1)
				(type default)
			)
			(layer "F.Fab")
		)
		(fp_line
			(start 0.67945 -0.3048)
			(end 0.67945 0.3048)
			(stroke
				(width 0.1)
				(type default)
			)
			(layer "F.Fab")
		)
		(fp_line
			(start 0.67945 0.3048)
			(end 0.120396 0.3048)
			(stroke
				(width 0.1)
				(type default)
			)
			(layer "F.Fab")
		)
		(pad "1" smd circle
			(at -0.40005 0)
			(size 0 0)
			(layers "F.Cu" "F.Mask" "F.Paste")
			(net "GPU_BASE_STBY_EN_BUF_R")
		)
		(pad "2" smd circle
			(at 0.40005 0)
			(size 0 0)
			(layers "F.Cu" "F.Mask" "F.Paste")
			(net "GND")
		)
	)
)
